# T6G (Grand Teton) — schematic netlist excerpt (pin names and nets, part order shuffled) for the footprints in the layout excerpt that follows; sources: Cadence DE-HDL packaged netlist, KiCad conversion of 04192023_DAF0TMB3IC0_F0TG_MB_C_brd_V02_OCP.brd

R6214  Q_RES  10K 1% EMPTY  pkg 0402LF  page 176 : A = USB_CPU0_HUB1_MODE_SEL1 ; B = GND
R3718  Q_RES  0 5% CHIP  pkg 0402LF  page 252 : A = SMB_LM75_1_3V3AUX_SDA_R ; B = SMB_LM75_1_3V3AUX_SDA
C1114  Q_CAP  22UF 16V 20% EMPTY  pkg C0805  page 169 : A = P3V3_AUX_DSC_S1 ; B = GND

(kicad_pcb
	(version 20260206)
	(generator "pcbnew")
	(generator_version "10.0")
	(general
		(thickness 1.6)
		(legacy_teardrops no)
	)
	(paper "A4")
	(title_block
		(title "04192023_DAF0TMB3IC0_F0TG_MB_C_brd_V02_OCP.brd")
		(comment 1 "Grand Teton / footprints 3718-3720 of 8354")
	)
	(layers
		(0 "F.Cu" signal "TOP")
		(4 "In1.Cu" signal "GND")
		(6 "In2.Cu" signal "IN1")
		(8 "In3.Cu" signal "GND1")
		(10 "In4.Cu" signal "IN2")
		(12 "In5.Cu" signal "GND2")
		(14 "In6.Cu" signal "IN3")
		(16 "In7.Cu" signal "GND3")
		(18 "In8.Cu" signal "VCC")
		(20 "In9.Cu" signal "VCC1")
		(22 "In10.Cu" signal "GND4")
		(24 "In11.Cu" signal "IN4")
		(26 "In12.Cu" signal "GND5")
		(28 "In13.Cu" signal "IN5")
		(30 "In14.Cu" signal "GND6")
		(32 "In15.Cu" signal "IN6")
		(34 "In16.Cu" signal "GND7")
		(2 "B.Cu" signal "BOTTOM")
		(9 "F.Adhes" user "F.Adhesive")
		(11 "B.Adhes" user "B.Adhesive")
		(13 "F.Paste" user "Package Geometry/Pastemask Top")
		(15 "B.Paste" user "Package Geometry/Pastemask Bottom")
		(5 "F.SilkS" user "Ref Des/Silkscreen Top")
		(7 "B.SilkS" user "Ref Des/Silkscreen Bottom")
		(1 "F.Mask" user "Board Geometry/Soldermask Top")
		(3 "B.Mask" user "Board Geometry/Soldermask Bottom")
		(17 "Dwgs.User" user "User.Drawings")
		(19 "Cmts.User" user "User.Comments")
		(21 "Eco1.User" user "User.Eco1")
		(23 "Eco2.User" user "User.Eco2")
		(25 "Edge.Cuts" user "Board Geometry/Outline")
		(27 "Margin" user)
		(31 "F.CrtYd" user "Package Geometry/Place Bound Top")
		(29 "B.CrtYd" user "Package Geometry/Place Bound Bottom")
		(35 "F.Fab" user "Ref Des/Assembly Top")
		(33 "B.Fab" user "Ref Des/Assembly Bottom")
	)
	(footprint ""
		(layer "F.Cu")
		(at 257.242056 -117.89537 180)
		(property "Reference" "R3718"
			(at 0 0 180)
			(layer "F.SilkS")
			(hide yes)
			(effects
				(font
					(size 1.27 1.27)
				)
			)
		)
		(property "Value" ""
			(at 0 0 180)
			(layer "F.Fab")
			(effects
				(font
					(size 1.27 1.27)
				)
			)
		)
		(duplicate_pad_numbers_are_jumpers no)
		(fp_line
			(start 0.7874 0.4064)
			(end -0.7874 0.4064)
			(stroke
				(width 0.1524)
				(type default)
			)
			(layer "F.SilkS")
		)
		(fp_line
			(start 0.7874 -0.4064)
			(end 0.7874 0.4064)
			(stroke
				(width 0.1524)
				(type default)
			)
			(layer "F.SilkS")
		)
		(fp_line
			(start -0.7874 0.4064)
			(end -0.7874 -0.4064)
			(stroke
				(width 0.1524)
				(type default)
			)
			(layer "F.SilkS")
		)
		(fp_line
			(start -0.7874 -0.4064)
			(end 0.7874 -0.4064)
			(stroke
				(width 0.1524)
				(type default)
			)
			(layer "F.SilkS")
		)
		(fp_line
			(start 0.67945 0.3048)
			(end 0.120396 0.3048)
			(stroke
				(width 0.1)
				(type default)
			)
			(layer "F.Fab")
		)
		(fp_line
			(start 0.67945 -0.3048)
			(end 0.67945 0.3048)
			(stroke
				(width 0.1)
				(type default)
			)
			(layer "F.Fab")
		)
		(fp_line
			(start 0.12065 -0.2794)
			(end 0.12065 -0.3048)
			(stroke
				(width 0.1)
				(type default)
			)
			(layer "F.Fab")
		)
		(fp_line
			(start 0.12065 -0.3048)
			(end 0.67945 -0.3048)
			(stroke
				(width 0.1)
				(type default)
			)
			(layer "F.Fab")
		)
		(fp_line
			(start 0.120396 0.3048)
			(end 0.120396 0.2794)
			(stroke
				(width 0.1)
				(type default)
			)
			(layer "F.Fab")
		)
		(fp_line
			(start 0.120396 0.2794)
			(end -0.12065 0.2794)
			(stroke
				(width 0.1)
				(type default)
			)
			(layer "F.Fab")
		)
		(fp_line
			(start -0.12065 0.3048)
			(end -0.67945 0.3048)
			(stroke
				(width 0.1)
				(type default)
			)
			(layer "F.Fab")
		)
		(fp_line
			(start -0.12065 0.2794)
			(end -0.12065 0.3048)
			(stroke
				(width 0.1)
				(type default)
			)
			(layer "F.Fab")
		)
		(fp_line
			(start -0.12065 -0.2794)
			(end 0.12065 -0.2794)
			(stroke
				(width 0.1)
				(type default)
			)
			(layer "F.Fab")
		)
		(fp_line
			(start -0.12065 -0.305054)
			(end -0.12065 -0.2794)
			(stroke
				(width 0.1)
				(type default)
			)
			(layer "F.Fab")
		)
		(fp_line
			(start -0.67945 0.3048)
			(end -0.67945 -0.305054)
			(stroke
				(width 0.1)
				(type default)
			)
			(layer "F.Fab")
		)
		(fp_line
			(start -0.67945 -0.305054)
			(end -0.12065 -0.305054)
			(stroke
				(width 0.1)
				(type default)
			)
			(layer "F.Fab")
		)
		(pad "1" smd circle
			(at -0.40005 0 180)
			(size 0 0)
			(layers "F.Cu" "F.Mask" "F.Paste")
			(net "SMB_LM75_1_3V3AUX_SDA_R")
		)
		(pad "2" smd circle
			(at 0.40005 0 180)
			(size 0 0)
			(layers "F.Cu" "F.Mask" "F.Paste")
			(net "SMB_LM75_1_3V3AUX_SDA")
		)
	)
	(footprint ""
		(layer "F.Cu")
		(at 47.91456 -105.08234)
		(property "Reference" "C1114"
			(at 0 0 0)
			(layer "F.SilkS")
			(hide yes)
			(effects
				(font
					(size 1.27 1.27)
				)
			)
		)
		(property "Value" ""
			(at 0 0 0)
			(layer "F.Fab")
			(effects
				(font
					(size 1.27 1.27)
				)
			)
		)
		(duplicate_pad_numbers_are_jumpers no)
		(fp_line
			(start -1.524 -0.762)
			(end 1.524 -0.762)
			(stroke
				(width 0.1524)
				(type default)
			)
			(layer "F.SilkS")
		)
		(fp_line
			(start -1.524 0.762)
			(end -1.524 -0.762)
			(stroke
				(width 0.1524)
				(type default)
			)
			(layer "F.SilkS")
		)
		(fp_line
			(start 1.524 -0.762)
			(end 1.524 0.762)
			(stroke
				(width 0.1524)
				(type default)
			)
			(layer "F.SilkS")
		)
		(fp_line
			(start 1.524 0.762)
			(end -1.524 0.762)
			(stroke
				(width 0.1524)
				(type default)
			)
			(layer "F.SilkS")
		)
		(fp_line
			(start -1.1049 -0.724916)
			(end -1.1049 0.724916)
			(stroke
				(width 0.1)
				(type default)
			)
			(layer "F.Fab")
		)
		(fp_line
			(start -1.1049 0.724916)
			(end 1.1049 0.724916)
			(stroke
				(width 0.1)
				(type default)
			)
			(layer "F.Fab")
		)
		(fp_line
			(start 1.1049 -0.724916)
			(end -1.1049 -0.724916)
			(stroke
				(width 0.1)
				(type default)
			)
			(layer "F.Fab")
		)
		(fp_line
			(start 1.1049 0.724916)
			(end 1.1049 -0.724916)
			(stroke
				(width 0.1)
				(type default)
			)
			(layer "F.Fab")
		)
		(pad "1" smd rect
			(at -0.889 0 180)
			(size 1.016 1.27)
			(layers "F.Cu" "F.Mask" "F.Paste")
			(net "P3V3_AUX_DSC_S1")
		)
		(pad "2" smd rect
			(at 0.889 0 180)
			(size 1.016 1.27)
			(layers "F.Cu" "F.Mask" "F.Paste")
			(net "GND")
		)
	)
	(footprint ""
		(layer "F.Cu")
		(at 126.804928 -50.169064 180)
		(property "Reference" "R6214"
			(at 0 0 180)
			(layer "F.SilkS")
			(hide yes)
			(effects
				(font
					(size 1.27 1.27)
				)
			)
		)
		(property "Value" ""
			(at 0 0 180)
			(layer "F.Fab")
			(effects
				(font
					(size 1.27 1.27)
				)
			)
		)
		(duplicate_pad_numbers_are_jumpers no)
		(fp_line
			(start 0.7874 0.4064)
			(end -0.7874 0.4064)
			(stroke
				(width 0.1524)
				(type default)
			)
			(layer "F.SilkS")
		)
		(fp_line
			(start 0.7874 -0.4064)
			(end 0.7874 0.4064)
			(stroke
				(width 0.1524)
				(type default)
			)
			(layer "F.SilkS")
		)
		(fp_line
			(start -0.7874 0.4064)
			(end -0.7874 -0.4064)
			(stroke
				(width 0.1524)
				(type default)
			)
			(layer "F.SilkS")
		)
		(fp_line
			(start -0.7874 -0.4064)
			(end 0.7874 -0.4064)
			(stroke
				(width 0.1524)
				(type default)
			)
			(layer "F.SilkS")
		)
		(fp_line
			(start 0.67945 0.3048)
			(end 0.120396 0.3048)
			(stroke
				(width 0.1)
				(type default)
			)
			(layer "F.Fab")
		)
		(fp_line
			(start 0.67945 -0.3048)
			(end 0.67945 0.3048)
			(stroke
				(width 0.1)
				(type default)
			)
			(layer "F.Fab")
		)
		(fp_line
			(start 0.12065 -0.2794)
			(end 0.12065 -0.3048)
			(stroke
				(width 0.1)
				(type default)
			)
			(layer "F.Fab")
		)
		(fp_line
			(start 0.12065 -0.3048)
			(end 0.67945 -0.3048)
			(stroke
				(width 0.1)
				(type default)
			)
			(layer "F.Fab")
		)
		(fp_line
			(start 0.120396 0.3048)
			(end 0.120396 0.2794)
			(stroke
				(width 0.1)
				(type default)
			)
			(layer "F.Fab")
		)
		(fp_line
			(start 0.120396 0.2794)
			(end -0.12065 0.2794)
			(stroke
				(width 0.1)
				(type default)
			)
			(layer "F.Fab")
		)
		(fp_line
			(start -0.12065 0.3048)
			(end -0.67945 0.3048)
			(stroke
				(width 0.1)
				(type default)
			)
			(layer "F.Fab")
		)
		(fp_line
			(start -0.12065 0.2794)
			(end -0.12065 0.3048)
			(stroke
				(width 0.1)
				(type default)
			)
			(layer "F.Fab")
		)
		(fp_line
			(start -0.12065 -0.2794)
			(end 0.12065 -0.2794)
			(stroke
				(width 0.1)
				(type default)
			)
			(layer "F.Fab")
		)
		(fp_line
			(start -0.12065 -0.305054)
			(end -0.12065 -0.2794)
			(stroke
				(width 0.1)
				(type default)
			)
			(layer "F.Fab")
		)
		(fp_line
			(start -0.67945 0.3048)
			(end -0.67945 -0.305054)
			(stroke
				(width 0.1)
				(type default)
			)
			(layer "F.Fab")
		)
		(fp_line
			(start -0.67945 -0.305054)
			(end -0.12065 -0.305054)
			(stroke
				(width 0.1)
				(type default)
			)
			(layer "F.Fab")
		)
		(pad "1" smd circle
			(at -0.40005 0 180)
			(size 0 0)
			(layers "F.Cu" "F.Mask" "F.Paste")
			(net "USB_CPU0_HUB1_MODE_SEL1")
		)
		(pad "2" smd circle
			(at 0.40005 0 180)
			(size 0 0)
			(layers "F.Cu" "F.Mask" "F.Paste")
			(net "GND")
		)
	)
)
